(kicad_pcb
	(version 20260206)
	(generator "pcbnew")
	(generator_version "10.0")
	(general
		(thickness 1.6)
		(legacy_teardrops no)
	)
	(paper "A4")
	(title_block
		(title "12092022_DA0F0TMDCD0_F0T_Management_Board_D_brd_V3_OCP.brd")
		(comment 1 "Grand Teton / footprints 757-761 of 1440")
	)
	(layers
		(0 "F.Cu" signal "TOP")
		(4 "In1.Cu" signal "GND")
		(6 "In2.Cu" signal "IN1")
		(8 "In3.Cu" signal "GND1")
		(10 "In4.Cu" signal "IN2")
		(12 "In5.Cu" signal "VCC")
		(14 "In6.Cu" signal "VCC1")
		(16 "In7.Cu" signal "IN3")
		(18 "In8.Cu" signal "GND2")
		(20 "In9.Cu" signal "IN4")
		(22 "In10.Cu" signal "GND3")
		(2 "B.Cu" signal "BOTTOM")
		(9 "F.Adhes" user "F.Adhesive")
		(11 "B.Adhes" user "B.Adhesive")
		(13 "F.Paste" user "Package Geometry/Pastemask Top")
		(15 "B.Paste" user "Package Geometry/Pastemask Bottom")
		(5 "F.SilkS" user "Ref Des/Silkscreen Top")
		(7 "B.SilkS" user "Ref Des/Silkscreen Bottom")
		(1 "F.Mask" user "Board Geometry/Soldermask Top")
		(3 "B.Mask" user "Board Geometry/Soldermask Bottom")
		(17 "Dwgs.User" user "User.Drawings")
		(19 "Cmts.User" user "User.Comments")
		(21 "Eco1.User" user "User.Eco1")
		(23 "Eco2.User" user "User.Eco2")
		(25 "Edge.Cuts" user "Board Geometry/Outline")
		(27 "Margin" user)
		(31 "F.CrtYd" user "Package Geometry/Place Bound Top")
		(29 "B.CrtYd" user "Package Geometry/Place Bound Bottom")
		(35 "F.Fab" user "Ref Des/Assembly Top")
		(33 "B.Fab" user "Ref Des/Assembly Bottom")
	)
	(footprint ""
		(layer "B.Cu")
		(at 47.340774 -49.363122)
		(property "Reference" "C88"
			(at 0 0 0)
			(layer "B.SilkS")
			(hide yes)
			(effects
				(font
					(size 1.27 1.27)
				)
				(justify mirror)
			)
		)
		(property "Value" ""
			(at 0 0 0)
			(layer "B.Fab")
			(effects
				(font
					(size 1.27 1.27)
				)
				(justify mirror)
			)
		)
		(duplicate_pad_numbers_are_jumpers no)
		(fp_line
			(start -0.7874 -0.4064)
			(end -0.7874 0.4064)
			(stroke
				(width 0.1524)
				(type default)
			)
			(layer "B.SilkS")
		)
		(fp_line
			(start -0.7874 0.4064)
			(end 0.7874 0.4064)
			(stroke
				(width 0.1524)
				(type default)
			)
			(layer "B.SilkS")
		)
		(fp_line
			(start 0.7874 -0.4064)
			(end -0.7874 -0.4064)
			(stroke
				(width 0.1524)
				(type default)
			)
			(layer "B.SilkS")
		)
		(fp_line
			(start 0.7874 0.4064)
			(end 0.7874 -0.4064)
			(stroke
				(width 0.1524)
				(type default)
			)
			(layer "B.SilkS")
		)
		(fp_line
			(start -0.67945 -0.3048)
			(end -0.67945 0.3048)
			(stroke
				(width 0.1)
				(type default)
			)
			(layer "B.Fab")
		)
		(fp_line
			(start -0.67945 0.3048)
			(end -0.120396 0.3048)
			(stroke
				(width 0.1)
				(type default)
			)
			(layer "B.Fab")
		)
		(fp_line
			(start -0.12065 -0.3048)
			(end -0.67945 -0.3048)
			(stroke
				(width 0.1)
				(type default)
			)
			(layer "B.Fab")
		)
		(fp_line
			(start -0.12065 -0.2794)
			(end -0.12065 -0.3048)
			(stroke
				(width 0.1)
				(type default)
			)
			(layer "B.Fab")
		)
		(fp_line
			(start -0.120396 0.2794)
			(end 0.12065 0.2794)
			(stroke
				(width 0.1)
				(type default)
			)
			(layer "B.Fab")
		)
		(fp_line
			(start -0.120396 0.3048)
			(end -0.120396 0.2794)
			(stroke
				(width 0.1)
				(type default)
			)
			(layer "B.Fab")
		)
		(fp_line
			(start 0.12065 -0.305054)
			(end 0.12065 -0.2794)
			(stroke
				(width 0.1)
				(type default)
			)
			(layer "B.Fab")
		)
		(fp_line
			(start 0.12065 -0.2794)
			(end -0.12065 -0.2794)
			(stroke
				(width 0.1)
				(type default)
			)
			(layer "B.Fab")
		)
		(fp_line
			(start 0.12065 0.2794)
			(end 0.12065 0.3048)
			(stroke
				(width 0.1)
				(type default)
			)
			(layer "B.Fab")
		)
		(fp_line
			(start 0.12065 0.3048)
			(end 0.67945 0.3048)
			(stroke
				(width 0.1)
				(type default)
			)
			(layer "B.Fab")
		)
		(fp_line
			(start 0.67945 -0.305054)
			(end 0.12065 -0.305054)
			(stroke
				(width 0.1)
				(type default)
			)
			(layer "B.Fab")
		)
		(fp_line
			(start 0.67945 0.3048)
			(end 0.67945 -0.305054)
			(stroke
				(width 0.1)
				(type default)
			)
			(layer "B.Fab")
		)
		(pad "1" smd circle
			(at 0.40005 0 180)
			(size 0 0)
			(layers "B.Cu" "B.Mask" "B.Paste")
			(net "P3V3_AUX")
		)
		(pad "2" smd circle
			(at -0.40005 0 180)
			(size 0 0)
			(layers "B.Cu" "B.Mask" "B.Paste")
			(net "GND")
		)
	)
	(footprint ""
		(layer "B.Cu")
		(at 112.014 27.178 90)
		(property "Reference" "X13"
			(at 1.86563 3.2385 0)
			(unlocked yes)
			(layer "B.SilkS")
			(effects
				(font
					(size 0.7874 0.5842)
					(thickness 0.1524)
				)
				(justify left mirror)
			)
		)
		(property "Value" ""
			(at 0 0 90)
			(layer "B.Fab")
			(effects
				(font
					(size 1.27 1.27)
				)
				(justify mirror)
			)
		)
		(property "Device Type" "TP_TDR_4P_FTS_TH-TP_TDR_4P_DIPA"
			(at -1.30175 1.27 0)
			(unlocked yes)
			(layer "B.Fab")
			(hide yes)
			(effects
				(font
					(size 0.635 0.4064)
					(thickness 0.1524)
				)
				(justify mirror)
			)
		)
		(property "User Part Number" "N_A"
			(at -1.30175 1.27 0)
			(unlocked yes)
			(layer "Cmts.User")
			(hide yes)
			(effects
				(font
					(size 0.635 0.4064)
					(thickness 0.1524)
				)
				(justify mirror)
			)
		)
		(duplicate_pad_numbers_are_jumpers no)
		(fp_line
			(start 0 -1.27)
			(end 0 -0.635)
			(stroke
				(width 0.1524)
				(type default)
			)
			(layer "B.SilkS")
		)
		(fp_line
			(start -2.54 -1.27)
			(end 0 -1.27)
			(stroke
				(width 0.1524)
				(type default)
			)
			(layer "B.SilkS")
		)
		(fp_line
			(start -2.54 -1.1303)
			(end -2.54 -1.27)
			(stroke
				(width 0.1524)
				(type default)
			)
			(layer "B.SilkS")
		)
		(fp_line
			(start 0 0.635)
			(end 0 1.905)
			(stroke
				(width 0.1524)
				(type default)
			)
			(layer "B.SilkS")
		)
		(fp_line
			(start -2.54 1.4097)
			(end -2.54 1.1303)
			(stroke
				(width 0.1524)
				(type default)
			)
			(layer "B.SilkS")
		)
		(fp_line
			(start 0 3.175)
			(end 0 3.81)
			(stroke
				(width 0.1524)
				(type default)
			)
			(layer "B.SilkS")
		)
		(fp_line
			(start 0 3.81)
			(end -2.54 3.81)
			(stroke
				(width 0.1524)
				(type default)
			)
			(layer "B.SilkS")
		)
		(fp_line
			(start -2.54 3.81)
			(end -2.54 3.6703)
			(stroke
				(width 0.1524)
				(type default)
			)
			(layer "B.SilkS")
		)
		(fp_poly
			(pts
				(xy 0.761746 0) (xy 2.285746 -0.762) (xy 2.285746 0.762)
			)
			(stroke
				(width 0)
				(type default)
			)
			(fill yes)
			(layer "B.SilkS")
		)
		(fp_line
			(start 0 -1.27)
			(end 0 3.81)
			(stroke
				(width 0.1)
				(type default)
			)
			(layer "B.Fab")
		)
		(fp_line
			(start -2.54 -1.27)
			(end 0 -1.27)
			(stroke
				(width 0.1)
				(type default)
			)
			(layer "B.Fab")
		)
		(fp_line
			(start 0 3.81)
			(end -2.54 3.81)
			(stroke
				(width 0.1)
				(type default)
			)
			(layer "B.Fab")
		)
		(fp_line
			(start -2.54 3.81)
			(end -2.54 -1.27)
			(stroke
				(width 0.1)
				(type default)
			)
			(layer "B.Fab")
		)
		(fp_poly
			(pts
				(xy 0.761746 0) (xy 2.285746 -0.762) (xy 2.285746 0.762)
			)
			(stroke
				(width 0)
				(type default)
			)
			(fill yes)
			(layer "B.Fab")
		)
		(pad "1" thru_hole circle
			(at 0 0 270)
			(size 1.0033 1.0033)
			(drill 0.249936)
			(layers "*.Cu" "*.Mask")
			(remove_unused_layers no)
			(net "TDR_DIFF_100_TOP_DP")
			(clearance 0.10795)
			(padstack
				(mode front_inner_back)
				(layer "Inner"
					(shape circle)
					(size 0.8001 0.8001)
					(clearance 0.1524)
				)
				(layer "B.Cu"
					(shape circle)
					(size 1.0033 1.0033)
					(thermal_gap 0.10795)
					(clearance 0.10795)
				)
			)
		)
		(pad "2" thru_hole circle
			(at -2.54 0 270)
			(size 1.9939 1.9939)
			(drill 0.249936)
			(layers "*.Cu" "*.Mask")
			(remove_unused_layers no)
			(net "GND_P1")
			(clearance 0.10795)
			(padstack
				(mode front_inner_back)
				(layer "Inner"
					(shape circle)
					(size 0.8001 0.8001)
					(clearance 0.1524)
				)
				(layer "B.Cu"
					(shape circle)
					(size 1.9939 1.9939)
					(thermal_gap 0.10795)
					(clearance 0.10795)
				)
			)
		)
		(pad "3" thru_hole circle
			(at -2.54 2.54 270)
			(size 1.9939 1.9939)
			(drill 0.249936)
			(layers "*.Cu" "*.Mask")
			(remove_unused_layers no)
			(net "GND_P1")
			(clearance 0.10795)
			(padstack
				(mode front_inner_back)
				(layer "Inner"
					(shape circle)
					(size 0.8001 0.8001)
					(clearance 0.1524)
				)
				(layer "B.Cu"
					(shape circle)
					(size 1.9939 1.9939)
					(thermal_gap 0.10795)
					(clearance 0.10795)
				)
			)
		)
		(pad "4" thru_hole circle
			(at 0 2.54 270)
			(size 1.0033 1.0033)
			(drill 0.249936)
			(layers "*.Cu" "*.Mask")
			(remove_unused_layers no)
			(net "TDR_DIFF_100_TOP_DN")
			(clearance 0.10795)
			(padstack
				(mode front_inner_back)
				(layer "Inner"
					(shape circle)
					(size 0.8001 0.8001)
					(clearance 0.1524)
				)
				(layer "B.Cu"
					(shape circle)
					(size 1.0033 1.0033)
					(thermal_gap 0.10795)
					(clearance 0.10795)
				)
			)
		)
	)
	(footprint ""
		(layer "B.Cu")
		(at 48.895254 -63.946278 90)
		(property "Reference" "R448"
			(at 0 0 90)
			(layer "B.SilkS")
			(hide yes)
			(effects
				(font
					(size 1.27 1.27)
				)
				(justify mirror)
			)
		)
		(property "Value" ""
			(at 0 0 90)
			(layer "B.Fab")
			(effects
				(font
					(size 1.27 1.27)
				)
				(justify mirror)
			)
		)
		(duplicate_pad_numbers_are_jumpers no)
		(fp_line
			(start 0.7874 -0.4064)
			(end -0.7874 -0.4064)
			(stroke
				(width 0.1524)
				(type default)
			)
			(layer "B.SilkS")
		)
		(fp_line
			(start -0.7874 -0.4064)
			(end -0.7874 0.4064)
			(stroke
				(width 0.1524)
				(type default)
			)
			(layer "B.SilkS")
		)
		(fp_line
			(start 0.7874 0.4064)
			(end 0.7874 -0.4064)
			(stroke
				(width 0.1524)
				(type default)
			)
			(layer "B.SilkS")
		)
		(fp_line
			(start -0.7874 0.4064)
			(end 0.7874 0.4064)
			(stroke
				(width 0.1524)
				(type default)
			)
			(layer "B.SilkS")
		)
		(fp_line
			(start 0.67945 -0.305054)
			(end 0.12065 -0.305054)
			(stroke
				(width 0.1)
				(type default)
			)
			(layer "B.Fab")
		)
		(fp_line
			(start 0.12065 -0.305054)
			(end 0.12065 -0.2794)
			(stroke
				(width 0.1)
				(type default)
			)
			(layer "B.Fab")
		)
		(fp_line
			(start -0.12065 -0.3048)
			(end -0.67945 -0.3048)
			(stroke
				(width 0.1)
				(type default)
			)
			(layer "B.Fab")
		)
		(fp_line
			(start -0.67945 -0.3048)
			(end -0.67945 0.3048)
			(stroke
				(width 0.1)
				(type default)
			)
			(layer "B.Fab")
		)
		(fp_line
			(start 0.12065 -0.2794)
			(end -0.12065 -0.2794)
			(stroke
				(width 0.1)
				(type default)
			)
			(layer "B.Fab")
		)
		(fp_line
			(start -0.12065 -0.2794)
			(end -0.12065 -0.3048)
			(stroke
				(width 0.1)
				(type default)
			)
			(layer "B.Fab")
		)
		(fp_line
			(start 0.12065 0.2794)
			(end 0.12065 0.3048)
			(stroke
				(width 0.1)
				(type default)
			)
			(layer "B.Fab")
		)
		(fp_line
			(start -0.120396 0.2794)
			(end 0.12065 0.2794)
			(stroke
				(width 0.1)
				(type default)
			)
			(layer "B.Fab")
		)
		(fp_line
			(start 0.67945 0.3048)
			(end 0.67945 -0.305054)
			(stroke
				(width 0.1)
				(type default)
			)
			(layer "B.Fab")
		)
		(fp_line
			(start 0.12065 0.3048)
			(end 0.67945 0.3048)
			(stroke
				(width 0.1)
				(type default)
			)
			(layer "B.Fab")
		)
		(fp_line
			(start -0.120396 0.3048)
			(end -0.120396 0.2794)
			(stroke
				(width 0.1)
				(type default)
			)
			(layer "B.Fab")
		)
		(fp_line
			(start -0.67945 0.3048)
			(end -0.120396 0.3048)
			(stroke
				(width 0.1)
				(type default)
			)
			(layer "B.Fab")
		)
		(pad "1" smd circle
			(at 0.40005 0 270)
			(size 0 0)
			(layers "B.Cu" "B.Mask" "B.Paste")
			(net "SMB_BMC_ALERT9_N")
		)
		(pad "2" smd circle
			(at -0.40005 0 270)
			(size 0 0)
			(layers "B.Cu" "B.Mask" "B.Paste")
			(net "SMB_BMC_ALERT9_R_N")
		)
	)
	(footprint ""
		(layer "B.Cu")
		(at 41.5036 -3.6068 90)
		(property "Reference" "R30"
			(at 0 0 90)
			(layer "B.SilkS")
			(hide yes)
			(effects
				(font
					(size 1.27 1.27)
				)
				(justify mirror)
			)
		)
		(property "Value" ""
			(at 0 0 90)
			(layer "B.Fab")
			(effects
				(font
					(size 1.27 1.27)
				)
				(justify mirror)
			)
		)
		(duplicate_pad_numbers_are_jumpers no)
		(fp_line
			(start 0.7874 -0.4064)
			(end -0.7874 -0.4064)
			(stroke
				(width 0.1524)
				(type default)
			)
			(layer "B.SilkS")
		)
		(fp_line
			(start -0.7874 -0.4064)
			(end -0.7874 0.4064)
			(stroke
				(width 0.1524)
				(type default)
			)
			(layer "B.SilkS")
		)
		(fp_line
			(start 0.7874 0.4064)
			(end 0.7874 -0.4064)
			(stroke
				(width 0.1524)
				(type default)
			)
			(layer "B.SilkS")
		)
		(fp_line
			(start -0.7874 0.4064)
			(end 0.7874 0.4064)
			(stroke
				(width 0.1524)
				(type default)
			)
			(layer "B.SilkS")
		)
		(fp_line
			(start 0.67945 -0.305054)
			(end 0.12065 -0.305054)
			(stroke
				(width 0.1)
				(type default)
			)
			(layer "B.Fab")
		)
		(fp_line
			(start 0.12065 -0.305054)
			(end 0.12065 -0.2794)
			(stroke
				(width 0.1)
				(type default)
			)
			(layer "B.Fab")
		)
		(fp_line
			(start -0.12065 -0.3048)
			(end -0.67945 -0.3048)
			(stroke
				(width 0.1)
				(type default)
			)
			(layer "B.Fab")
		)
		(fp_line
			(start -0.67945 -0.3048)
			(end -0.67945 0.3048)
			(stroke
				(width 0.1)
				(type default)
			)
			(layer "B.Fab")
		)
		(fp_line
			(start 0.12065 -0.2794)
			(end -0.12065 -0.2794)
			(stroke
				(width 0.1)
				(type default)
			)
			(layer "B.Fab")
		)
		(fp_line
			(start -0.12065 -0.2794)
			(end -0.12065 -0.3048)
			(stroke
				(width 0.1)
				(type default)
			)
			(layer "B.Fab")
		)
		(fp_line
			(start 0.12065 0.2794)
			(end 0.12065 0.3048)
			(stroke
				(width 0.1)
				(type default)
			)
			(layer "B.Fab")
		)
		(fp_line
			(start -0.120396 0.2794)
			(end 0.12065 0.2794)
			(stroke
				(width 0.1)
				(type default)
			)
			(layer "B.Fab")
		)
		(fp_line
			(start 0.67945 0.3048)
			(end 0.67945 -0.305054)
			(stroke
				(width 0.1)
				(type default)
			)
			(layer "B.Fab")
		)
		(fp_line
			(start 0.12065 0.3048)
			(end 0.67945 0.3048)
			(stroke
				(width 0.1)
				(type default)
			)
			(layer "B.Fab")
		)
		(fp_line
			(start -0.120396 0.3048)
			(end -0.120396 0.2794)
			(stroke
				(width 0.1)
				(type default)
			)
			(layer "B.Fab")
		)
		(fp_line
			(start -0.67945 0.3048)
			(end -0.120396 0.3048)
			(stroke
				(width 0.1)
				(type default)
			)
			(layer "B.Fab")
		)
		(pad "1" smd circle
			(at 0.40005 0 270)
			(size 0 0)
			(layers "B.Cu" "B.Mask" "B.Paste")
			(net "CRT_VCC5")
		)
		(pad "2" smd circle
			(at -0.40005 0 270)
			(size 0 0)
			(layers "B.Cu" "B.Mask" "B.Paste")
			(net "BMC_DDC_BUF_EN")
		)
	)
	(footprint ""
		(layer "B.Cu")
		(at 85.29955 -48.504094 180)
		(property "Reference" "R366"
			(at 0 0 0)
			(layer "B.SilkS")
			(hide yes)
			(effects
				(font
					(size 1.27 1.27)
				)
				(justify mirror)
			)
		)
		(property "Value" ""
			(at 0 0 0)
			(layer "B.Fab")
			(effects
				(font
					(size 1.27 1.27)
				)
				(justify mirror)
			)
		)
		(duplicate_pad_numbers_are_jumpers no)
		(fp_line
			(start 0.7874 0.4064)
			(end 0.7874 -0.4064)
			(stroke
				(width 0.1524)
				(type default)
			)
			(layer "B.SilkS")
		)
		(fp_line
			(start 0.7874 -0.4064)
			(end -0.7874 -0.4064)
			(stroke
				(width 0.1524)
				(type default)
			)
			(layer "B.SilkS")
		)
		(fp_line
			(start -0.7874 0.4064)
			(end 0.7874 0.4064)
			(stroke
				(width 0.1524)
				(type default)
			)
			(layer "B.SilkS")
		)
		(fp_line
			(start -0.7874 -0.4064)
			(end -0.7874 0.4064)
			(stroke
				(width 0.1524)
				(type default)
			)
			(layer "B.SilkS")
		)
		(fp_line
			(start 0.67945 0.3048)
			(end 0.67945 -0.305054)
			(stroke
				(width 0.1)
				(type default)
			)
			(layer "B.Fab")
		)
		(fp_line
			(start 0.67945 -0.305054)
			(end 0.12065 -0.305054)
			(stroke
				(width 0.1)
				(type default)
			)
			(layer "B.Fab")
		)
		(fp_line
			(start 0.12065 0.3048)
			(end 0.67945 0.3048)
			(stroke
				(width 0.1)
				(type default)
			)
			(layer "B.Fab")
		)
		(fp_line
			(start 0.12065 0.2794)
			(end 0.12065 0.3048)
			(stroke
				(width 0.1)
				(type default)
			)
			(layer "B.Fab")
		)
		(fp_line
			(start 0.12065 -0.2794)
			(end -0.12065 -0.2794)
			(stroke
				(width 0.1)
				(type default)
			)
			(layer "B.Fab")
		)
		(fp_line
			(start 0.12065 -0.305054)
			(end 0.12065 -0.2794)
			(stroke
				(width 0.1)
				(type default)
			)
			(layer "B.Fab")
		)
		(fp_line
			(start -0.120396 0.3048)
			(end -0.120396 0.2794)
			(stroke
				(width 0.1)
				(type default)
			)
			(layer "B.Fab")
		)
		(fp_line
			(start -0.120396 0.2794)
			(end 0.12065 0.2794)
			(stroke
				(width 0.1)
				(type default)
			)
			(layer "B.Fab")
		)
		(fp_line
			(start -0.12065 -0.2794)
			(end -0.12065 -0.3048)
			(stroke
				(width 0.1)
				(type default)
			)
			(layer "B.Fab")
		)
		(fp_line
			(start -0.12065 -0.3048)
			(end -0.67945 -0.3048)
			(stroke
				(width 0.1)
				(type default)
			)
			(layer "B.Fab")
		)
		(fp_line
			(start -0.67945 0.3048)
			(end -0.120396 0.3048)
			(stroke
				(width 0.1)
				(type default)
			)
			(layer "B.Fab")
		)
		(fp_line
			(start -0.67945 -0.3048)
			(end -0.67945 0.3048)
			(stroke
				(width 0.1)
				(type default)
			)
			(layer "B.Fab")
		)
		(pad "1" smd circle
			(at 0.40005 0)
			(size 0 0)
			(layers "B.Cu" "B.Mask" "B.Paste")
			(net "M_BMC_DDR4_MCAS_N")
		)
		(pad "2" smd circle
			(at -0.40005 0)
			(size 0 0)
			(layers "B.Cu" "B.Mask" "B.Paste")
			(net "P1V2_AUX")
		)
	)
)
